# T6G (Grand Teton) — schematic netlist excerpt (pin names and nets, part order shuffled) for the footprints in the layout excerpt that follows; sources: Cadence DE-HDL packaged netlist, KiCad conversion of 04192023_DAF0TMB3IC0_F0TG_MB_C_brd_V02_OCP.brd

R8249  Q_RES  0 5% CHIP  pkg 0402LF  page 217 : A = SMB_SCM_2_R1_SDA ; B = SMB_DIO_PVDDCR_CPU1_P1_R
PC178  Q_CAP  560PF 50V 10% EMPTY  pkg C0402  page 194 : A = SW_PVDDCR_CPU0_P0_SW1 ; B = SW_PVDDCR_CPU0_P0_SW1_RC
C6696  Q_CAP_DIFFBUS  DIFF BUS_0.22UF 6.3V 20% X6S  pkg C0201  page 341 : \1\ = P5E_CPU1_P2_TX_BUF_C_DN<1> ; \2\ = P5E_CPU1_P2_TX_BUF_DN<1>

(kicad_pcb
	(version 20260206)
	(generator "pcbnew")
	(generator_version "10.0")
	(general
		(thickness 1.6)
		(legacy_teardrops no)
	)
	(paper "A4")
	(title_block
		(title "04192023_DAF0TMB3IC0_F0TG_MB_C_brd_V02_OCP.brd")
		(comment 1 "Grand Teton / footprints 4764-4766 of 8354")
	)
	(layers
		(0 "F.Cu" signal "TOP")
		(4 "In1.Cu" signal "GND")
		(6 "In2.Cu" signal "IN1")
		(8 "In3.Cu" signal "GND1")
		(10 "In4.Cu" signal "IN2")
		(12 "In5.Cu" signal "GND2")
		(14 "In6.Cu" signal "IN3")
		(16 "In7.Cu" signal "GND3")
		(18 "In8.Cu" signal "VCC")
		(20 "In9.Cu" signal "VCC1")
		(22 "In10.Cu" signal "GND4")
		(24 "In11.Cu" signal "IN4")
		(26 "In12.Cu" signal "GND5")
		(28 "In13.Cu" signal "IN5")
		(30 "In14.Cu" signal "GND6")
		(32 "In15.Cu" signal "IN6")
		(34 "In16.Cu" signal "GND7")
		(2 "B.Cu" signal "BOTTOM")
		(9 "F.Adhes" user "F.Adhesive")
		(11 "B.Adhes" user "B.Adhesive")
		(13 "F.Paste" user "Package Geometry/Pastemask Top")
		(15 "B.Paste" user "Package Geometry/Pastemask Bottom")
		(5 "F.SilkS" user "Ref Des/Silkscreen Top")
		(7 "B.SilkS" user "Ref Des/Silkscreen Bottom")
		(1 "F.Mask" user "Board Geometry/Soldermask Top")
		(3 "B.Mask" user "Board Geometry/Soldermask Bottom")
		(17 "Dwgs.User" user "User.Drawings")
		(19 "Cmts.User" user "User.Comments")
		(21 "Eco1.User" user "User.Eco1")
		(23 "Eco2.User" user "User.Eco2")
		(25 "Edge.Cuts" user "Board Geometry/Outline")
		(27 "Margin" user)
		(31 "F.CrtYd" user "Package Geometry/Place Bound Top")
		(29 "B.CrtYd" user "Package Geometry/Place Bound Bottom")
		(35 "F.Fab" user "Ref Des/Assembly Top")
		(33 "B.Fab" user "Ref Des/Assembly Bottom")
	)
	(footprint ""
		(layer "F.Cu")
		(at 368.0079 -180.77561)
		(property "Reference" "PC178"
			(at 0 0 0)
			(layer "F.SilkS")
			(hide yes)
			(effects
				(font
					(size 1.27 1.27)
				)
			)
		)
		(property "Value" ""
			(at 0 0 0)
			(layer "F.Fab")
			(effects
				(font
					(size 1.27 1.27)
				)
			)
		)
		(duplicate_pad_numbers_are_jumpers no)
		(fp_line
			(start -0.7874 -0.4064)
			(end 0.7874 -0.4064)
			(stroke
				(width 0.1524)
				(type default)
			)
			(layer "F.SilkS")
		)
		(fp_line
			(start -0.7874 0.4064)
			(end -0.7874 -0.4064)
			(stroke
				(width 0.1524)
				(type default)
			)
			(layer "F.SilkS")
		)
		(fp_line
			(start 0.7874 -0.4064)
			(end 0.7874 0.4064)
			(stroke
				(width 0.1524)
				(type default)
			)
			(layer "F.SilkS")
		)
		(fp_line
			(start 0.7874 0.4064)
			(end -0.7874 0.4064)
			(stroke
				(width 0.1524)
				(type default)
			)
			(layer "F.SilkS")
		)
		(fp_line
			(start -0.67945 -0.305054)
			(end -0.12065 -0.305054)
			(stroke
				(width 0.1)
				(type default)
			)
			(layer "F.Fab")
		)
		(fp_line
			(start -0.67945 0.3048)
			(end -0.67945 -0.305054)
			(stroke
				(width 0.1)
				(type default)
			)
			(layer "F.Fab")
		)
		(fp_line
			(start -0.12065 -0.305054)
			(end -0.12065 -0.2794)
			(stroke
				(width 0.1)
				(type default)
			)
			(layer "F.Fab")
		)
		(fp_line
			(start -0.12065 -0.2794)
			(end 0.12065 -0.2794)
			(stroke
				(width 0.1)
				(type default)
			)
			(layer "F.Fab")
		)
		(fp_line
			(start -0.12065 0.2794)
			(end -0.12065 0.3048)
			(stroke
				(width 0.1)
				(type default)
			)
			(layer "F.Fab")
		)
		(fp_line
			(start -0.12065 0.3048)
			(end -0.67945 0.3048)
			(stroke
				(width 0.1)
				(type default)
			)
			(layer "F.Fab")
		)
		(fp_line
			(start 0.120396 0.2794)
			(end -0.12065 0.2794)
			(stroke
				(width 0.1)
				(type default)
			)
			(layer "F.Fab")
		)
		(fp_line
			(start 0.120396 0.3048)
			(end 0.120396 0.2794)
			(stroke
				(width 0.1)
				(type default)
			)
			(layer "F.Fab")
		)
		(fp_line
			(start 0.12065 -0.3048)
			(end 0.67945 -0.3048)
			(stroke
				(width 0.1)
				(type default)
			)
			(layer "F.Fab")
		)
		(fp_line
			(start 0.12065 -0.2794)
			(end 0.12065 -0.3048)
			(stroke
				(width 0.1)
				(type default)
			)
			(layer "F.Fab")
		)
		(fp_line
			(start 0.67945 -0.3048)
			(end 0.67945 0.3048)
			(stroke
				(width 0.1)
				(type default)
			)
			(layer "F.Fab")
		)
		(fp_line
			(start 0.67945 0.3048)
			(end 0.120396 0.3048)
			(stroke
				(width 0.1)
				(type default)
			)
			(layer "F.Fab")
		)
		(pad "1" smd circle
			(at -0.40005 0)
			(size 0 0)
			(layers "F.Cu" "F.Mask" "F.Paste")
			(net "SW_PVDDCR_CPU0_P0_SW1")
		)
		(pad "2" smd circle
			(at 0.40005 0)
			(size 0 0)
			(layers "F.Cu" "F.Mask" "F.Paste")
			(net "SW_PVDDCR_CPU0_P0_SW1_RC")
		)
	)
	(footprint ""
		(layer "F.Cu")
		(at 24.765 -367.919)
		(property "Reference" "R8249"
			(at 0 0 0)
			(layer "F.SilkS")
			(hide yes)
			(effects
				(font
					(size 1.27 1.27)
				)
			)
		)
		(property "Value" ""
			(at 0 0 0)
			(layer "F.Fab")
			(effects
				(font
					(size 1.27 1.27)
				)
			)
		)
		(duplicate_pad_numbers_are_jumpers no)
		(fp_line
			(start -0.7874 -0.4064)
			(end 0.7874 -0.4064)
			(stroke
				(width 0.1524)
				(type default)
			)
			(layer "F.SilkS")
		)
		(fp_line
			(start -0.7874 0.4064)
			(end -0.7874 -0.4064)
			(stroke
				(width 0.1524)
				(type default)
			)
			(layer "F.SilkS")
		)
		(fp_line
			(start 0.7874 -0.4064)
			(end 0.7874 0.4064)
			(stroke
				(width 0.1524)
				(type default)
			)
			(layer "F.SilkS")
		)
		(fp_line
			(start 0.7874 0.4064)
			(end -0.7874 0.4064)
			(stroke
				(width 0.1524)
				(type default)
			)
			(layer "F.SilkS")
		)
		(fp_line
			(start -0.67945 -0.305054)
			(end -0.12065 -0.305054)
			(stroke
				(width 0.1)
				(type default)
			)
			(layer "F.Fab")
		)
		(fp_line
			(start -0.67945 0.3048)
			(end -0.67945 -0.305054)
			(stroke
				(width 0.1)
				(type default)
			)
			(layer "F.Fab")
		)
		(fp_line
			(start -0.12065 -0.305054)
			(end -0.12065 -0.2794)
			(stroke
				(width 0.1)
				(type default)
			)
			(layer "F.Fab")
		)
		(fp_line
			(start -0.12065 -0.2794)
			(end 0.12065 -0.2794)
			(stroke
				(width 0.1)
				(type default)
			)
			(layer "F.Fab")
		)
		(fp_line
			(start -0.12065 0.2794)
			(end -0.12065 0.3048)
			(stroke
				(width 0.1)
				(type default)
			)
			(layer "F.Fab")
		)
		(fp_line
			(start -0.12065 0.3048)
			(end -0.67945 0.3048)
			(stroke
				(width 0.1)
				(type default)
			)
			(layer "F.Fab")
		)
		(fp_line
			(start 0.120396 0.2794)
			(end -0.12065 0.2794)
			(stroke
				(width 0.1)
				(type default)
			)
			(layer "F.Fab")
		)
		(fp_line
			(start 0.120396 0.3048)
			(end 0.120396 0.2794)
			(stroke
				(width 0.1)
				(type default)
			)
			(layer "F.Fab")
		)
		(fp_line
			(start 0.12065 -0.3048)
			(end 0.67945 -0.3048)
			(stroke
				(width 0.1)
				(type default)
			)
			(layer "F.Fab")
		)
		(fp_line
			(start 0.12065 -0.2794)
			(end 0.12065 -0.3048)
			(stroke
				(width 0.1)
				(type default)
			)
			(layer "F.Fab")
		)
		(fp_line
			(start 0.67945 -0.3048)
			(end 0.67945 0.3048)
			(stroke
				(width 0.1)
				(type default)
			)
			(layer "F.Fab")
		)
		(fp_line
			(start 0.67945 0.3048)
			(end 0.120396 0.3048)
			(stroke
				(width 0.1)
				(type default)
			)
			(layer "F.Fab")
		)
		(pad "1" smd circle
			(at -0.40005 0)
			(size 0 0)
			(layers "F.Cu" "F.Mask" "F.Paste")
			(net "SMB_SCM_2_R1_SDA")
		)
		(pad "2" smd circle
			(at 0.40005 0)
			(size 0 0)
			(layers "F.Cu" "F.Mask" "F.Paste")
			(net "SMB_DIO_PVDDCR_CPU1_P1_R")
		)
	)
	(footprint ""
		(layer "F.Cu")
		(at 117.931946 -408.517344 -90)
		(property "Reference" "C6696"
			(at 0 0 270)
			(layer "F.SilkS")
			(hide yes)
			(effects
				(font
					(size 1.27 1.27)
				)
			)
		)
		(property "Value" ""
			(at 0 0 270)
			(layer "F.Fab")
			(effects
				(font
					(size 1.27 1.27)
				)
			)
		)
		(duplicate_pad_numbers_are_jumpers no)
		(fp_line
			(start -0.299974 0.150114)
			(end -0.299974 -0.150114)
			(stroke
				(width 0.1)
				(type default)
			)
			(layer "F.Fab")
		)
		(fp_line
			(start 0.299974 0.150114)
			(end -0.299974 0.150114)
			(stroke
				(width 0.1)
				(type default)
			)
			(layer "F.Fab")
		)
		(fp_line
			(start -0.299974 -0.150114)
			(end 0.299974 -0.150114)
			(stroke
				(width 0.1)
				(type default)
			)
			(layer "F.Fab")
		)
		(fp_line
			(start 0.299974 -0.150114)
			(end 0.299974 0.150114)
			(stroke
				(width 0.1)
				(type default)
			)
			(layer "F.Fab")
		)
		(pad "1" smd rect
			(at -0.2667 0 270)
			(size 0.3048 0.381)
			(layers "F.Cu" "F.Mask" "F.Paste")
			(net "P5E_CPU1_P2_TX_BUF_C_DN<1>")
		)
		(pad "2" smd rect
			(at 0.2667 0 270)
			(size 0.3048 0.381)
			(layers "F.Cu" "F.Mask" "F.Paste")
			(net "P5E_CPU1_P2_TX_BUF_DN<1>")
		)
	)
)
